# TIMECARD (Time Appliance Project (Time Card)) — schematic netlist excerpt (pin names and nets, part order shuffled) for the footprints in the layout excerpt that follows; sources: Cadence DE-HDL packaged netlist, KiCad conversion of R4006-B0001-02_R01.brd

ME11  MEC_MTH8  pkg MTH125C236N_V8  page 34
  \1\  = SG
  \2\  = SG
  \3\  = SG
  \4\  = SG
  \5\  = SG
  \6\  = SG
  \7\  = SG
  \8\  = SG

SP53  NULL  pkg DUMMY  page 34

(kicad_pcb
	(version 20260206)
	(generator "pcbnew")
	(generator_version "10.0")
	(general
		(thickness 1.6)
		(legacy_teardrops no)
	)
	(paper "A4")
	(title_block
		(title "timecard-production-celestica-r4006 — R4006-B0001-02_R01.brd")
		(comment 1 "Time Appliance Project (Time Card) / footprints 436-437 of 1113")
	)
	(layers
		(0 "F.Cu" signal "TOP")
		(4 "In1.Cu" signal "L02_GND1")
		(6 "In2.Cu" signal "L03_SIG1")
		(8 "In3.Cu" signal "L04_GND2")
		(10 "In4.Cu" signal "L05_VCC1")
		(12 "In5.Cu" signal "L06_VCC2")
		(14 "In6.Cu" signal "L07_GND3")
		(16 "In7.Cu" signal "L08_SIG2")
		(18 "In8.Cu" signal "L09_GND4")
		(2 "B.Cu" signal "BOTTOM")
		(9 "F.Adhes" user "F.Adhesive")
		(11 "B.Adhes" user "B.Adhesive")
		(13 "F.Paste" user "Package Geometry/Pastemask Top")
		(15 "B.Paste" user "Package Geometry/Pastemask Bottom")
		(5 "F.SilkS" user "Ref Des/Silkscreen Top")
		(7 "B.SilkS" user "Ref Des/Silkscreen Bottom")
		(1 "F.Mask" user "Board Geometry/Soldermask Top")
		(3 "B.Mask" user "Board Geometry/Soldermask Bottom")
		(17 "Dwgs.User" user "User.Drawings")
		(19 "Cmts.User" user "User.Comments")
		(21 "Eco1.User" user "User.Eco1")
		(23 "Eco2.User" user "User.Eco2")
		(25 "Edge.Cuts" user "Board Geometry/Outline")
		(27 "Margin" user)
		(31 "F.CrtYd" user "Package Geometry/Place Bound Top")
		(29 "B.CrtYd" user "Package Geometry/Place Bound Bottom")
		(35 "F.Fab" user "Ref Des/Assembly Top")
		(33 "B.Fab" user "Ref Des/Assembly Bottom")
	)
	(footprint ""
		(layer "F.Cu")
		(at 162.569906 -106.13009)
		(property "Reference" "ME11"
			(at 0.625094 4.31546 0)
			(unlocked yes)
			(layer "F.SilkS")
			(effects
				(font
					(size 0.7874 0.5842)
					(thickness 0.1524)
				)
			)
		)
		(property "Value" ""
			(at 0 0 0)
			(layer "F.Fab")
			(effects
				(font
					(size 1.27 1.27)
				)
			)
		)
		(property "Device Type" "MEC_MTH8-MTH125C236N_V8-MTH125A"
			(at 0 5.08127 0)
			(unlocked yes)
			(layer "F.Fab")
			(hide yes)
			(effects
				(font
					(size 0.7874 0.5842)
					(thickness 0.1524)
				)
			)
		)
		(duplicate_pad_numbers_are_jumpers no)
		(fp_poly
			(pts
				(arc
					(start 3.5052 0)
					(mid -3.5052 0)
					(end 3.5052 0)
				)
			)
			(stroke
				(width 0)
				(type default)
			)
			(fill no)
			(layer "B.CrtYd")
		)
		(fp_poly
			(pts
				(arc
					(start 3.5052 0)
					(mid -3.5052 0)
					(end 3.5052 0)
				)
			)
			(stroke
				(width 0)
				(type default)
			)
			(fill no)
			(layer "F.CrtYd")
		)
		(fp_circle
			(center 0 0)
			(end 2.9972 0)
			(stroke
				(width 0.1)
				(type default)
			)
			(fill no)
			(layer "B.Fab")
		)
		(fp_circle
			(center 0 0)
			(end 2.9972 0)
			(stroke
				(width 0.1)
				(type default)
			)
			(fill no)
			(layer "F.Fab")
		)
		(pad "" np_thru_hole circle
			(at 0 0)
			(size 2.921 2.921)
			(drill 3.175)
			(layers "*.Cu" "*.Mask")
			(padstack
				(mode front_inner_back)
				(layer "Inner"
					(shape circle)
					(size 2.921 2.921)
					(clearance 0.4445)
				)
				(layer "B.Cu"
					(shape circle)
					(size 2.921 2.921)
				)
			)
		)
		(pad "1" thru_hole circle
			(at 0 -2.4511)
			(size 0.6096 0.6096)
			(drill 0.3048)
			(layers "*.Cu" "*.Mask")
			(remove_unused_layers no)
			(net "SG")
			(padstack
				(mode front_inner_back)
				(layer "Inner"
					(shape circle)
					(size 0.6096 0.6096)
					(clearance 0.1143)
				)
				(layer "B.Cu"
					(shape circle)
					(size 0.6096 0.6096)
				)
			)
		)
		(pad "2" thru_hole circle
			(at 1.733296 -1.733296)
			(size 0.6096 0.6096)
			(drill 0.3048)
			(layers "*.Cu" "*.Mask")
			(remove_unused_layers no)
			(net "SG")
			(padstack
				(mode front_inner_back)
				(layer "Inner"
					(shape circle)
					(size 0.6096 0.6096)
					(clearance 0.1143)
				)
				(layer "B.Cu"
					(shape circle)
					(size 0.6096 0.6096)
				)
			)
		)
		(pad "3" thru_hole circle
			(at 2.4511 0)
			(size 0.6096 0.6096)
			(drill 0.3048)
			(layers "*.Cu" "*.Mask")
			(remove_unused_layers no)
			(net "SG")
			(padstack
				(mode front_inner_back)
				(layer "Inner"
					(shape circle)
					(size 0.6096 0.6096)
					(clearance 0.1143)
				)
				(layer "B.Cu"
					(shape circle)
					(size 0.6096 0.6096)
				)
			)
		)
		(pad "4" thru_hole circle
			(at 1.733296 1.733296)
			(size 0.6096 0.6096)
			(drill 0.3048)
			(layers "*.Cu" "*.Mask")
			(remove_unused_layers no)
			(net "SG")
			(padstack
				(mode front_inner_back)
				(layer "Inner"
					(shape circle)
					(size 0.6096 0.6096)
					(clearance 0.1143)
				)
				(layer "B.Cu"
					(shape circle)
					(size 0.6096 0.6096)
				)
			)
		)
		(pad "5" thru_hole circle
			(at 0 2.4511)
			(size 0.6096 0.6096)
			(drill 0.3048)
			(layers "*.Cu" "*.Mask")
			(remove_unused_layers no)
			(net "SG")
			(padstack
				(mode front_inner_back)
				(layer "Inner"
					(shape circle)
					(size 0.6096 0.6096)
					(clearance 0.1143)
				)
				(layer "B.Cu"
					(shape circle)
					(size 0.6096 0.6096)
				)
			)
		)
		(pad "6" thru_hole circle
			(at -1.733296 1.733296)
			(size 0.6096 0.6096)
			(drill 0.3048)
			(layers "*.Cu" "*.Mask")
			(remove_unused_layers no)
			(net "SG")
			(padstack
				(mode front_inner_back)
				(layer "Inner"
					(shape circle)
					(size 0.6096 0.6096)
					(clearance 0.1143)
				)
				(layer "B.Cu"
					(shape circle)
					(size 0.6096 0.6096)
				)
			)
		)
		(pad "7" thru_hole circle
			(at -2.4511 0)
			(size 0.6096 0.6096)
			(drill 0.3048)
			(layers "*.Cu" "*.Mask")
			(remove_unused_layers no)
			(net "SG")
			(padstack
				(mode front_inner_back)
				(layer "Inner"
					(shape circle)
					(size 0.6096 0.6096)
					(clearance 0.1143)
				)
				(layer "B.Cu"
					(shape circle)
					(size 0.6096 0.6096)
				)
			)
		)
		(pad "8" thru_hole circle
			(at -1.733296 -1.733296)
			(size 0.6096 0.6096)
			(drill 0.3048)
			(layers "*.Cu" "*.Mask")
			(remove_unused_layers no)
			(net "SG")
			(padstack
				(mode front_inner_back)
				(layer "Inner"
					(shape circle)
					(size 0.6096 0.6096)
					(clearance 0.1143)
				)
				(layer "B.Cu"
					(shape circle)
					(size 0.6096 0.6096)
				)
			)
		)
		(zone
			(layers "F.Cu" "B.Cu" "In1.Cu" "In2.Cu" "In3.Cu" "In4.Cu" "In5.Cu" "In6.Cu"
				"In7.Cu" "In8.Cu"
			)
			(hatch none 0.5)
			(connect_pads
				(clearance 0)
			)
			(min_thickness 0.25)
			(keepout
				(tracks not_allowed)
				(vias allowed)
				(pads allowed)
				(copperpour not_allowed)
				(footprints allowed)
			)
			(placement
				(enabled no)
				(sheetname "")
			)
			(fill
				(thermal_gap 0.5)
				(thermal_bridge_width 0.5)
				(island_removal_mode 0)
			)
			(polygon
				(pts
					(arc
						(start 164.462206 -106.13009)
						(mid 160.677606 -106.13009)
						(end 164.462206 -106.13009)
					)
				)
			)
		)
	)
	(footprint ""
		(layer "F.Cu")
		(at 48.514 -130.683)
		(property "Reference" "SP53"
			(at 0 0 0)
			(layer "F.SilkS")
			(hide yes)
			(effects
				(font
					(size 1.27 1.27)
				)
			)
		)
		(property "Value" ""
			(at 0 0 0)
			(layer "F.Fab")
			(effects
				(font
					(size 1.27 1.27)
				)
			)
		)
		(duplicate_pad_numbers_are_jumpers no)
	)
)
